# S9S_MB_2U (Grand Teton) — schematic netlist excerpt (pin names and nets, part order shuffled) for the footprints in the layout excerpt that follows; sources: Cadence DE-HDL packaged netlist, KiCad conversion of 03242023_DA0F0TMBIJ0_F0T_Motherboard_J_brd_V01_OCP.brd

R3152  Q_RES  1K 1% CHIP  pkg 0402LF  page 164 : A = PD_SMB_OCP2_HP_ADD1 ; B = GND
R4039  Q_RES  1K 1% CHIP  pkg 0402LF  page 225 : A = P0V62_CPU0_RST_DDR_VREF ; B = GND

(kicad_pcb
	(version 20260206)
	(generator "pcbnew")
	(generator_version "10.0")
	(general
		(thickness 1.6)
		(legacy_teardrops no)
	)
	(paper "A4")
	(title_block
		(title "03242023_DA0F0TMBIJ0_F0T_Motherboard_J_brd_V01_OCP.brd")
		(comment 1 "Grand Teton / footprints 869-870 of 6105")
	)
	(layers
		(0 "F.Cu" signal "TOP")
		(4 "In1.Cu" signal "GND")
		(6 "In2.Cu" signal "IN1")
		(8 "In3.Cu" signal "GND1")
		(10 "In4.Cu" signal "IN2")
		(12 "In5.Cu" signal "GND2")
		(14 "In6.Cu" signal "IN3")
		(16 "In7.Cu" signal "GND3")
		(18 "In8.Cu" signal "VCC")
		(20 "In9.Cu" signal "VCC1")
		(22 "In10.Cu" signal "GND4")
		(24 "In11.Cu" signal "IN4")
		(26 "In12.Cu" signal "GND5")
		(28 "In13.Cu" signal "IN5")
		(30 "In14.Cu" signal "GND6")
		(32 "In15.Cu" signal "IN6")
		(34 "In16.Cu" signal "GND7")
		(2 "B.Cu" signal "BOTTOM")
		(9 "F.Adhes" user "F.Adhesive")
		(11 "B.Adhes" user "B.Adhesive")
		(13 "F.Paste" user "Package Geometry/Pastemask Top")
		(15 "B.Paste" user "Package Geometry/Pastemask Bottom")
		(5 "F.SilkS" user "Ref Des/Silkscreen Top")
		(7 "B.SilkS" user "Ref Des/Silkscreen Bottom")
		(1 "F.Mask" user "Board Geometry/Soldermask Top")
		(3 "B.Mask" user "Board Geometry/Soldermask Bottom")
		(17 "Dwgs.User" user "User.Drawings")
		(19 "Cmts.User" user "User.Comments")
		(21 "Eco1.User" user "User.Eco1")
		(23 "Eco2.User" user "User.Eco2")
		(25 "Edge.Cuts" user "Board Geometry/Outline")
		(27 "Margin" user)
		(31 "F.CrtYd" user "Package Geometry/Place Bound Top")
		(29 "B.CrtYd" user "Package Geometry/Place Bound Bottom")
		(35 "F.Fab" user "Ref Des/Assembly Top")
		(33 "B.Fab" user "Ref Des/Assembly Bottom")
	)
	(footprint ""
		(layer "F.Cu")
		(at 113.67008 -122.132598 90)
		(property "Reference" "R4039"
			(at 0 0 90)
			(layer "F.SilkS")
			(hide yes)
			(effects
				(font
					(size 1.27 1.27)
				)
			)
		)
		(property "Value" ""
			(at 0 0 90)
			(layer "F.Fab")
			(effects
				(font
					(size 1.27 1.27)
				)
			)
		)
		(duplicate_pad_numbers_are_jumpers no)
		(fp_line
			(start 0.7874 -0.4064)
			(end 0.7874 0.4064)
			(stroke
				(width 0.1524)
				(type default)
			)
			(layer "F.SilkS")
		)
		(fp_line
			(start -0.7874 -0.4064)
			(end 0.7874 -0.4064)
			(stroke
				(width 0.1524)
				(type default)
			)
			(layer "F.SilkS")
		)
		(fp_line
			(start 0.7874 0.4064)
			(end -0.7874 0.4064)
			(stroke
				(width 0.1524)
				(type default)
			)
			(layer "F.SilkS")
		)
		(fp_line
			(start -0.7874 0.4064)
			(end -0.7874 -0.4064)
			(stroke
				(width 0.1524)
				(type default)
			)
			(layer "F.SilkS")
		)
		(fp_line
			(start -0.12065 -0.305054)
			(end -0.12065 -0.2794)
			(stroke
				(width 0.1)
				(type default)
			)
			(layer "F.Fab")
		)
		(fp_line
			(start -0.67945 -0.305054)
			(end -0.12065 -0.305054)
			(stroke
				(width 0.1)
				(type default)
			)
			(layer "F.Fab")
		)
		(fp_line
			(start 0.67945 -0.3048)
			(end 0.67945 0.3048)
			(stroke
				(width 0.1)
				(type default)
			)
			(layer "F.Fab")
		)
		(fp_line
			(start 0.12065 -0.3048)
			(end 0.67945 -0.3048)
			(stroke
				(width 0.1)
				(type default)
			)
			(layer "F.Fab")
		)
		(fp_line
			(start 0.12065 -0.2794)
			(end 0.12065 -0.3048)
			(stroke
				(width 0.1)
				(type default)
			)
			(layer "F.Fab")
		)
		(fp_line
			(start -0.12065 -0.2794)
			(end 0.12065 -0.2794)
			(stroke
				(width 0.1)
				(type default)
			)
			(layer "F.Fab")
		)
		(fp_line
			(start 0.120396 0.2794)
			(end -0.12065 0.2794)
			(stroke
				(width 0.1)
				(type default)
			)
			(layer "F.Fab")
		)
		(fp_line
			(start -0.12065 0.2794)
			(end -0.12065 0.3048)
			(stroke
				(width 0.1)
				(type default)
			)
			(layer "F.Fab")
		)
		(fp_line
			(start 0.67945 0.3048)
			(end 0.120396 0.3048)
			(stroke
				(width 0.1)
				(type default)
			)
			(layer "F.Fab")
		)
		(fp_line
			(start 0.120396 0.3048)
			(end 0.120396 0.2794)
			(stroke
				(width 0.1)
				(type default)
			)
			(layer "F.Fab")
		)
		(fp_line
			(start -0.12065 0.3048)
			(end -0.67945 0.3048)
			(stroke
				(width 0.1)
				(type default)
			)
			(layer "F.Fab")
		)
		(fp_line
			(start -0.67945 0.3048)
			(end -0.67945 -0.305054)
			(stroke
				(width 0.1)
				(type default)
			)
			(layer "F.Fab")
		)
		(pad "1" smd circle
			(at -0.40005 0 90)
			(size 0 0)
			(layers "F.Cu" "F.Mask" "F.Paste")
			(net "P0V62_CPU0_RST_DDR_VREF")
		)
		(pad "2" smd circle
			(at 0.40005 0 90)
			(size 0 0)
			(layers "F.Cu" "F.Mask" "F.Paste")
			(net "GND")
		)
	)
	(footprint ""
		(layer "F.Cu")
		(at 131.6736 -125.758448 180)
		(property "Reference" "R3152"
			(at 0 0 180)
			(layer "F.SilkS")
			(hide yes)
			(effects
				(font
					(size 1.27 1.27)
				)
			)
		)
		(property "Value" ""
			(at 0 0 180)
			(layer "F.Fab")
			(effects
				(font
					(size 1.27 1.27)
				)
			)
		)
		(duplicate_pad_numbers_are_jumpers no)
		(fp_line
			(start 0.7874 0.4064)
			(end -0.7874 0.4064)
			(stroke
				(width 0.1524)
				(type default)
			)
			(layer "F.SilkS")
		)
		(fp_line
			(start 0.7874 -0.4064)
			(end 0.7874 0.4064)
			(stroke
				(width 0.1524)
				(type default)
			)
			(layer "F.SilkS")
		)
		(fp_line
			(start -0.7874 0.4064)
			(end -0.7874 -0.4064)
			(stroke
				(width 0.1524)
				(type default)
			)
			(layer "F.SilkS")
		)
		(fp_line
			(start -0.7874 -0.4064)
			(end 0.7874 -0.4064)
			(stroke
				(width 0.1524)
				(type default)
			)
			(layer "F.SilkS")
		)
		(fp_line
			(start 0.67945 0.3048)
			(end 0.120396 0.3048)
			(stroke
				(width 0.1)
				(type default)
			)
			(layer "F.Fab")
		)
		(fp_line
			(start 0.67945 -0.3048)
			(end 0.67945 0.3048)
			(stroke
				(width 0.1)
				(type default)
			)
			(layer "F.Fab")
		)
		(fp_line
			(start 0.12065 -0.2794)
			(end 0.12065 -0.3048)
			(stroke
				(width 0.1)
				(type default)
			)
			(layer "F.Fab")
		)
		(fp_line
			(start 0.12065 -0.3048)
			(end 0.67945 -0.3048)
			(stroke
				(width 0.1)
				(type default)
			)
			(layer "F.Fab")
		)
		(fp_line
			(start 0.120396 0.3048)
			(end 0.120396 0.2794)
			(stroke
				(width 0.1)
				(type default)
			)
			(layer "F.Fab")
		)
		(fp_line
			(start 0.120396 0.2794)
			(end -0.12065 0.2794)
			(stroke
				(width 0.1)
				(type default)
			)
			(layer "F.Fab")
		)
		(fp_line
			(start -0.12065 0.3048)
			(end -0.67945 0.3048)
			(stroke
				(width 0.1)
				(type default)
			)
			(layer "F.Fab")
		)
		(fp_line
			(start -0.12065 0.2794)
			(end -0.12065 0.3048)
			(stroke
				(width 0.1)
				(type default)
			)
			(layer "F.Fab")
		)
		(fp_line
			(start -0.12065 -0.2794)
			(end 0.12065 -0.2794)
			(stroke
				(width 0.1)
				(type default)
			)
			(layer "F.Fab")
		)
		(fp_line
			(start -0.12065 -0.305054)
			(end -0.12065 -0.2794)
			(stroke
				(width 0.1)
				(type default)
			)
			(layer "F.Fab")
		)
		(fp_line
			(start -0.67945 0.3048)
			(end -0.67945 -0.305054)
			(stroke
				(width 0.1)
				(type default)
			)
			(layer "F.Fab")
		)
		(fp_line
			(start -0.67945 -0.305054)
			(end -0.12065 -0.305054)
			(stroke
				(width 0.1)
				(type default)
			)
			(layer "F.Fab")
		)
		(pad "1" smd circle
			(at -0.40005 0 180)
			(size 0 0)
			(layers "F.Cu" "F.Mask" "F.Paste")
			(net "PD_SMB_OCP2_HP_ADD1")
		)
		(pad "2" smd circle
			(at 0.40005 0 180)
			(size 0 0)
			(layers "F.Cu" "F.Mask" "F.Paste")
			(net "GND")
		)
	)
)
